(kicad_pcb
	(version 20260206)
	(generator "pcbnew")
	(generator_version "10.0")
	(general
		(thickness 1.6)
		(legacy_teardrops no)
	)
	(paper "A4")
	(title_block
		(title "peb — Lightning_PEB_BRD.brd")
		(comment 1 "Lightning (Wiwynn / Facebook NVMe JBOF) / footprints 1028-1035 of 2563")
	)
	(layers
		(0 "F.Cu" signal "TOP")
		(4 "In1.Cu" signal "L2GND")
		(6 "In2.Cu" signal "L3")
		(8 "In3.Cu" signal "L4VCC")
		(10 "In4.Cu" signal "L5VCC")
		(12 "In5.Cu" signal "L6")
		(14 "In6.Cu" signal "L7GND")
		(2 "B.Cu" signal "BOTTOM")
		(9 "F.Adhes" user "F.Adhesive")
		(11 "B.Adhes" user "B.Adhesive")
		(13 "F.Paste" user "Package Geometry/Pastemask Top")
		(15 "B.Paste" user "Package Geometry/Pastemask Bottom")
		(5 "F.SilkS" user "Ref Des/Silkscreen Top")
		(7 "B.SilkS" user "Ref Des/Silkscreen Bottom")
		(1 "F.Mask" user "Board Geometry/Soldermask Top")
		(3 "B.Mask" user "Board Geometry/Soldermask Bottom")
		(17 "Dwgs.User" user "User.Drawings")
		(19 "Cmts.User" user "User.Comments")
		(21 "Eco1.User" user "User.Eco1")
		(23 "Eco2.User" user "User.Eco2")
		(25 "Edge.Cuts" user "Board Geometry/Outline")
		(27 "Margin" user)
		(31 "F.CrtYd" user "Package Geometry/Place Bound Top")
		(29 "B.CrtYd" user "Package Geometry/Place Bound Bottom")
		(35 "F.Fab" user "Ref Des/Assembly Top")
		(33 "B.Fab" user "Ref Des/Assembly Bottom")
	)
	(footprint ""
		(layer "F.Cu")
		(at 53.200046 -36.471098 90)
		(property "Reference" "R629"
			(at 0 0 90)
			(layer "F.SilkS")
			(hide yes)
			(effects
				(font
					(size 1.27 1.27)
				)
			)
		)
		(property "Value" "10KR2F-2-GP"
			(at 0.064008 -3.993896 90)
			(unlocked yes)
			(layer "F.Fab")
			(hide yes)
			(effects
				(font
					(size 1.016 1.016)
					(thickness 0.1524)
				)
			)
		)
		(property "Device Type" "R402H16"
			(at 0.064008 -5.517896 90)
			(unlocked yes)
			(layer "F.Fab")
			(hide yes)
			(effects
				(font
					(size 1.016 1.016)
					(thickness 0.1524)
				)
			)
		)
		(duplicate_pad_numbers_are_jumpers no)
		(fp_line
			(start 0.508 -0.9398)
			(end -0.508 -0.9398)
			(stroke
				(width 0.1524)
				(type default)
			)
			(layer "F.SilkS")
		)
		(fp_line
			(start -0.508 -0.9398)
			(end -0.508 0.9398)
			(stroke
				(width 0.1524)
				(type default)
			)
			(layer "F.SilkS")
		)
		(fp_rect
			(start -0.508 0.9398)
			(end 0.508 -0.9398)
			(stroke
				(width 0)
				(type default)
			)
			(fill no)
			(layer "F.CrtYd")
		)
		(fp_rect
			(start -0.508 0.9398)
			(end 0.508 -0.9398)
			(stroke
				(width 0)
				(type default)
			)
			(fill no)
			(layer "F.Fab")
		)
		(pad "1" smd custom
			(at 0 -0.4445 90)
			(size 0.1397 0.1397)
			(layers "F.Cu" "F.Mask" "F.Paste")
			(net "Q42_D")
			(options
				(clearance outline)
				(anchor circle)
			)
			(primitives
				(gr_poly
					(pts
						(arc
							(start -0.1778 -0.2794)
							(mid -0.249642 -0.249642)
							(end -0.2794 -0.1778)
						)
						(arc
							(start -0.2794 0.1778)
							(mid -0.249642 0.249642)
							(end -0.1778 0.2794)
						)
						(arc
							(start 0.1778 0.2794)
							(mid 0.249642 0.249642)
							(end 0.2794 0.1778)
						)
						(arc
							(start 0.2794 -0.1778)
							(mid 0.249642 -0.249642)
							(end 0.1778 -0.2794)
						)
					)
					(width 0)
					(fill yes)
				)
			)
		)
		(pad "2" smd custom
			(at 0 0.4445 90)
			(size 0.1397 0.1397)
			(layers "F.Cu" "F.Mask" "F.Paste")
			(net "Q43_B")
			(options
				(clearance outline)
				(anchor circle)
			)
			(primitives
				(gr_poly
					(pts
						(arc
							(start -0.1778 -0.2794)
							(mid -0.249642 -0.249642)
							(end -0.2794 -0.1778)
						)
						(arc
							(start -0.2794 0.1778)
							(mid -0.249642 0.249642)
							(end -0.1778 0.2794)
						)
						(arc
							(start 0.1778 0.2794)
							(mid 0.249642 0.249642)
							(end 0.2794 0.1778)
						)
						(arc
							(start 0.2794 -0.1778)
							(mid 0.249642 -0.249642)
							(end 0.1778 -0.2794)
						)
					)
					(width 0)
					(fill yes)
				)
			)
		)
	)
	(footprint ""
		(layer "F.Cu")
		(at 125.599952 -19.99996 90)
		(property "Reference" "LED8"
			(at 0 0 90)
			(layer "F.SilkS")
			(hide yes)
			(effects
				(font
					(size 1.27 1.27)
				)
			)
		)
		(property "Value" "LED-YG-51-GP"
			(at -2.6924 -1.4224 90)
			(unlocked yes)
			(layer "F.Fab")
			(hide yes)
			(effects
				(font
					(size 1.016 1.016)
					(thickness 0.1524)
				)
			)
		)
		(property "Device Type" "LED1608AKH40"
			(at -2.6924 -2.9464 90)
			(unlocked yes)
			(layer "F.Fab")
			(hide yes)
			(effects
				(font
					(size 1.016 1.016)
					(thickness 0.1524)
				)
			)
		)
		(duplicate_pad_numbers_are_jumpers no)
		(fp_line
			(start 0.6604 -1.3716)
			(end 0.6604 1.3716)
			(stroke
				(width 0.1524)
				(type default)
			)
			(layer "F.SilkS")
		)
		(fp_line
			(start -0.6604 -1.3716)
			(end 0.6604 -1.3716)
			(stroke
				(width 0.1524)
				(type default)
			)
			(layer "F.SilkS")
		)
		(fp_line
			(start 0.6604 1.3716)
			(end -0.6604 1.3716)
			(stroke
				(width 0.1524)
				(type default)
			)
			(layer "F.SilkS")
		)
		(fp_line
			(start -0.6604 1.3716)
			(end -0.6604 -1.3716)
			(stroke
				(width 0.1524)
				(type default)
			)
			(layer "F.SilkS")
		)
		(fp_line
			(start -0.5969 1.5494)
			(end 0.5842 1.5494)
			(stroke
				(width 0.508)
				(type default)
			)
			(layer "F.SilkS")
		)
		(fp_line
			(start 0.7493 1.651)
			(end 0.7493 1.1811)
			(stroke
				(width 0.3302)
				(type default)
			)
			(layer "F.SilkS")
		)
		(fp_line
			(start -0.7493 1.651)
			(end -0.7493 1.1811)
			(stroke
				(width 0.3302)
				(type default)
			)
			(layer "F.SilkS")
		)
		(fp_rect
			(start -0.6223 1.3335)
			(end 0.6223 -1.3335)
			(stroke
				(width 0)
				(type default)
			)
			(fill no)
			(layer "F.CrtYd")
		)
		(fp_rect
			(start -0.6223 1.3335)
			(end 0.6223 -1.3335)
			(stroke
				(width 0)
				(type default)
			)
			(fill no)
			(layer "F.Fab")
		)
		(pad "A" smd custom
			(at 0 -0.762 90)
			(size 0.2159 0.2159)
			(layers "F.Cu" "F.Mask" "F.Paste")
			(net "LED_R_1")
			(options
				(clearance outline)
				(anchor circle)
			)
			(primitives
				(gr_poly
					(pts
						(arc
							(start -0.3302 -0.4318)
							(mid -0.402042 -0.402042)
							(end -0.4318 -0.3302)
						)
						(arc
							(start -0.4318 0.3302)
							(mid -0.402042 0.402042)
							(end -0.3302 0.4318)
						)
						(arc
							(start 0.3302 0.4318)
							(mid 0.402042 0.402042)
							(end 0.4318 0.3302)
						)
						(arc
							(start 0.4318 -0.3302)
							(mid 0.402042 -0.402042)
							(end 0.3302 -0.4318)
						)
					)
					(width 0)
					(fill yes)
				)
			)
		)
		(pad "K" smd custom
			(at 0 0.762 90)
			(size 0.2159 0.2159)
			(layers "F.Cu" "F.Mask" "F.Paste")
			(net "LED_Q_1")
			(options
				(clearance outline)
				(anchor circle)
			)
			(primitives
				(gr_poly
					(pts
						(arc
							(start -0.3302 -0.4318)
							(mid -0.402042 -0.402042)
							(end -0.4318 -0.3302)
						)
						(arc
							(start -0.4318 0.3302)
							(mid -0.402042 0.402042)
							(end -0.3302 0.4318)
						)
						(arc
							(start 0.3302 0.4318)
							(mid 0.402042 0.402042)
							(end 0.4318 0.3302)
						)
						(arc
							(start 0.4318 -0.3302)
							(mid 0.402042 -0.402042)
							(end 0.3302 -0.4318)
						)
					)
					(width 0)
					(fill yes)
				)
			)
		)
	)
	(footprint ""
		(layer "F.Cu")
		(at 55.118 -194.564 180)
		(property "Reference" "R885"
			(at 0 0 180)
			(layer "F.SilkS")
			(hide yes)
			(effects
				(font
					(size 1.27 1.27)
				)
			)
		)
		(property "Value" "10KR2F-2-GP"
			(at 0.064008 -3.993896 180)
			(unlocked yes)
			(layer "F.Fab")
			(hide yes)
			(effects
				(font
					(size 1.016 1.016)
					(thickness 0.1524)
				)
			)
		)
		(property "Device Type" "R402H16"
			(at 0.064008 -5.517896 180)
			(unlocked yes)
			(layer "F.Fab")
			(hide yes)
			(effects
				(font
					(size 1.016 1.016)
					(thickness 0.1524)
				)
			)
		)
		(duplicate_pad_numbers_are_jumpers no)
		(fp_line
			(start 0.508 -0.9398)
			(end -0.508 -0.9398)
			(stroke
				(width 0.1524)
				(type default)
			)
			(layer "F.SilkS")
		)
		(fp_line
			(start -0.508 -0.9398)
			(end -0.508 0.9398)
			(stroke
				(width 0.1524)
				(type default)
			)
			(layer "F.SilkS")
		)
		(fp_rect
			(start -0.508 0.9398)
			(end 0.508 -0.9398)
			(stroke
				(width 0)
				(type default)
			)
			(fill no)
			(layer "F.CrtYd")
		)
		(fp_rect
			(start -0.508 0.9398)
			(end 0.508 -0.9398)
			(stroke
				(width 0)
				(type default)
			)
			(fill no)
			(layer "F.Fab")
		)
		(pad "1" smd custom
			(at 0 -0.4445 180)
			(size 0.1397 0.1397)
			(layers "F.Cu" "F.Mask" "F.Paste")
			(net "P3V3_STBY")
			(options
				(clearance outline)
				(anchor circle)
			)
			(primitives
				(gr_poly
					(pts
						(arc
							(start -0.1778 -0.2794)
							(mid -0.249642 -0.249642)
							(end -0.2794 -0.1778)
						)
						(arc
							(start -0.2794 0.1778)
							(mid -0.249642 0.249642)
							(end -0.1778 0.2794)
						)
						(arc
							(start 0.1778 0.2794)
							(mid 0.249642 0.249642)
							(end 0.2794 0.1778)
						)
						(arc
							(start 0.2794 -0.1778)
							(mid 0.249642 -0.249642)
							(end 0.1778 -0.2794)
						)
					)
					(width 0)
					(fill yes)
				)
			)
		)
		(pad "2" smd custom
			(at 0 0.4445 180)
			(size 0.1397 0.1397)
			(layers "F.Cu" "F.Mask" "F.Paste")
			(net "I2C7_BUFF_EN")
			(options
				(clearance outline)
				(anchor circle)
			)
			(primitives
				(gr_poly
					(pts
						(arc
							(start -0.1778 -0.2794)
							(mid -0.249642 -0.249642)
							(end -0.2794 -0.1778)
						)
						(arc
							(start -0.2794 0.1778)
							(mid -0.249642 0.249642)
							(end -0.1778 0.2794)
						)
						(arc
							(start 0.1778 0.2794)
							(mid 0.249642 0.249642)
							(end 0.2794 0.1778)
						)
						(arc
							(start 0.2794 -0.1778)
							(mid 0.249642 -0.249642)
							(end 0.1778 -0.2794)
						)
					)
					(width 0)
					(fill yes)
				)
			)
		)
	)
	(footprint ""
		(layer "F.Cu")
		(at 52.607972 -212.420454 180)
		(property "Reference" "C364"
			(at 0 0 180)
			(layer "F.SilkS")
			(hide yes)
			(effects
				(font
					(size 1.27 1.27)
				)
			)
		)
		(property "Value" "SCD22U10V2KX-1GP"
			(at 1.1811 -2.7051 180)
			(unlocked yes)
			(layer "F.Fab")
			(hide yes)
			(effects
				(font
					(size 1.016 1.016)
					(thickness 0.1524)
				)
			)
		)
		(property "Device Type" "C402H22"
			(at 1.1811 -4.2291 180)
			(unlocked yes)
			(layer "F.Fab")
			(hide yes)
			(effects
				(font
					(size 1.016 1.016)
					(thickness 0.1524)
				)
			)
		)
		(duplicate_pad_numbers_are_jumpers no)
		(fp_rect
			(start -0.4318 0.9525)
			(end 0.4318 -0.9525)
			(stroke
				(width 0)
				(type default)
			)
			(fill no)
			(layer "F.CrtYd")
		)
		(fp_rect
			(start -0.4318 0.9525)
			(end 0.4318 -0.9525)
			(stroke
				(width 0)
				(type default)
			)
			(fill no)
			(layer "F.Fab")
		)
		(pad "1" smd custom
			(at 0 -0.4445 180)
			(size 0.1524 0.1524)
			(layers "F.Cu" "F.Mask" "F.Paste")
			(net "PCIE_TX_CAP_N74")
			(options
				(clearance outline)
				(anchor circle)
			)
			(primitives
				(gr_poly
					(pts
						(arc
							(start 0.3048 -0.2032)
							(mid 0.275042 -0.275042)
							(end 0.2032 -0.3048)
						)
						(arc
							(start -0.2032 -0.3048)
							(mid -0.275042 -0.275042)
							(end -0.3048 -0.2032)
						)
						(arc
							(start -0.3048 0.2032)
							(mid -0.275042 0.275042)
							(end -0.2032 0.3048)
						)
						(arc
							(start 0.2032 0.3048)
							(mid 0.275042 0.275042)
							(end 0.3048 0.2032)
						)
					)
					(width 0)
					(fill yes)
				)
			)
		)
		(pad "2" smd custom
			(at 0 0.4445 180)
			(size 0.1524 0.1524)
			(layers "F.Cu" "F.Mask" "F.Paste")
			(net "PCIE_TX_N74")
			(options
				(clearance outline)
				(anchor circle)
			)
			(primitives
				(gr_poly
					(pts
						(arc
							(start 0.3048 -0.2032)
							(mid 0.275042 -0.275042)
							(end 0.2032 -0.3048)
						)
						(arc
							(start -0.2032 -0.3048)
							(mid -0.275042 -0.275042)
							(end -0.3048 -0.2032)
						)
						(arc
							(start -0.3048 0.2032)
							(mid -0.275042 0.275042)
							(end -0.2032 0.3048)
						)
						(arc
							(start 0.2032 0.3048)
							(mid 0.275042 0.275042)
							(end 0.3048 0.2032)
						)
					)
					(width 0)
					(fill yes)
				)
			)
		)
	)
	(footprint ""
		(layer "F.Cu")
		(at 160.528 -81.9404 180)
		(property "Reference" "R44"
			(at 0 0 180)
			(layer "F.SilkS")
			(hide yes)
			(effects
				(font
					(size 1.27 1.27)
				)
			)
		)
		(property "Value" "10KR2F-2-GP"
			(at 0.064008 -3.993896 180)
			(unlocked yes)
			(layer "F.Fab")
			(hide yes)
			(effects
				(font
					(size 1.016 1.016)
					(thickness 0.1524)
				)
			)
		)
		(property "Device Type" "R402H16"
			(at 0.064008 -5.517896 180)
			(unlocked yes)
			(layer "F.Fab")
			(hide yes)
			(effects
				(font
					(size 1.016 1.016)
					(thickness 0.1524)
				)
			)
		)
		(duplicate_pad_numbers_are_jumpers no)
		(fp_line
			(start 0.508 -0.9398)
			(end -0.508 -0.9398)
			(stroke
				(width 0.1524)
				(type default)
			)
			(layer "F.SilkS")
		)
		(fp_line
			(start -0.508 -0.9398)
			(end -0.508 0.9398)
			(stroke
				(width 0.1524)
				(type default)
			)
			(layer "F.SilkS")
		)
		(fp_rect
			(start -0.508 0.9398)
			(end 0.508 -0.9398)
			(stroke
				(width 0)
				(type default)
			)
			(fill no)
			(layer "F.CrtYd")
		)
		(fp_rect
			(start -0.508 0.9398)
			(end 0.508 -0.9398)
			(stroke
				(width 0)
				(type default)
			)
			(fill no)
			(layer "F.Fab")
		)
		(pad "1" smd custom
			(at 0 -0.4445 180)
			(size 0.1397 0.1397)
			(layers "F.Cu" "F.Mask" "F.Paste")
			(net "GND")
			(options
				(clearance outline)
				(anchor circle)
			)
			(primitives
				(gr_poly
					(pts
						(arc
							(start -0.1778 -0.2794)
							(mid -0.249642 -0.249642)
							(end -0.2794 -0.1778)
						)
						(arc
							(start -0.2794 0.1778)
							(mid -0.249642 0.249642)
							(end -0.1778 0.2794)
						)
						(arc
							(start 0.1778 0.2794)
							(mid 0.249642 0.249642)
							(end 0.2794 0.1778)
						)
						(arc
							(start 0.2794 -0.1778)
							(mid 0.249642 -0.249642)
							(end 0.1778 -0.2794)
						)
					)
					(width 0)
					(fill yes)
				)
			)
		)
		(pad "2" smd custom
			(at 0 0.4445 180)
			(size 0.1397 0.1397)
			(layers "F.Cu" "F.Mask" "F.Paste")
			(net "PCIE_CLKGEN2_OE0")
			(options
				(clearance outline)
				(anchor circle)
			)
			(primitives
				(gr_poly
					(pts
						(arc
							(start -0.1778 -0.2794)
							(mid -0.249642 -0.249642)
							(end -0.2794 -0.1778)
						)
						(arc
							(start -0.2794 0.1778)
							(mid -0.249642 0.249642)
							(end -0.1778 0.2794)
						)
						(arc
							(start 0.1778 0.2794)
							(mid 0.249642 0.249642)
							(end 0.2794 0.1778)
						)
						(arc
							(start 0.2794 -0.1778)
							(mid 0.249642 -0.249642)
							(end 0.1778 -0.2794)
						)
					)
					(width 0)
					(fill yes)
				)
			)
		)
	)
	(footprint ""
		(layer "F.Cu")
		(at 50.292 -134.493)
		(property "Reference" "TP161"
			(at 0 0 0)
			(layer "F.SilkS")
			(hide yes)
			(effects
				(font
					(size 1.27 1.27)
				)
			)
		)
		(property "Value" "TPAD28-2-GP"
			(at -0.0127 -1.6637 0)
			(unlocked yes)
			(layer "F.Fab")
			(hide yes)
			(effects
				(font
					(size 1.016 1.016)
					(thickness 0.1524)
				)
			)
		)
		(property "Device Type" "TPAD28"
			(at -0.0127 -3.1877 0)
			(unlocked yes)
			(layer "F.Fab")
			(hide yes)
			(effects
				(font
					(size 1.016 1.016)
					(thickness 0.1524)
				)
			)
		)
		(duplicate_pad_numbers_are_jumpers no)
		(fp_poly
			(pts
				(arc
					(start 0.3556 0)
					(mid -0.3556 0)
					(end 0.3556 0)
				)
			)
			(stroke
				(width 0)
				(type default)
			)
			(fill no)
			(layer "F.CrtYd")
		)
		(fp_poly
			(pts
				(arc
					(start 0.6096 0)
					(mid -0.6096 0)
					(end 0.6096 0)
				)
			)
			(stroke
				(width 0)
				(type default)
			)
			(fill no)
			(layer "F.Fab")
		)
		(pad "1" smd circle
			(at 0 0)
			(size 0.7112 0.7112)
			(layers "F.Cu" "F.Mask" "F.Paste")
			(net "TP_BMC_GPIOJ6")
		)
	)
	(footprint ""
		(layer "F.Cu")
		(at 26.416 -72.6948 -90)
		(property "Reference" "TP165"
			(at 0 0 270)
			(layer "F.SilkS")
			(hide yes)
			(effects
				(font
					(size 1.27 1.27)
				)
			)
		)
		(property "Value" "TPAD28-2-GP"
			(at -0.0127 -1.6637 270)
			(unlocked yes)
			(layer "F.Fab")
			(hide yes)
			(effects
				(font
					(size 1.016 1.016)
					(thickness 0.1524)
				)
			)
		)
		(property "Device Type" "TPAD28"
			(at -0.0127 -3.1877 270)
			(unlocked yes)
			(layer "F.Fab")
			(hide yes)
			(effects
				(font
					(size 1.016 1.016)
					(thickness 0.1524)
				)
			)
		)
		(duplicate_pad_numbers_are_jumpers no)
		(fp_poly
			(pts
				(arc
					(start 0 -0.3556)
					(mid 0 0.3556)
					(end 0 -0.3556)
				)
			)
			(stroke
				(width 0)
				(type default)
			)
			(fill no)
			(layer "F.CrtYd")
		)
		(fp_poly
			(pts
				(arc
					(start 0 -0.6096)
					(mid 0 0.6096)
					(end 0 -0.6096)
				)
			)
			(stroke
				(width 0)
				(type default)
			)
			(fill no)
			(layer "F.Fab")
		)
		(pad "1" smd circle
			(at 0 0 270)
			(size 0.7112 0.7112)
			(layers "F.Cu" "F.Mask" "F.Paste")
			(net "NIC_JTDO")
		)
	)
	(footprint ""
		(layer "F.Cu")
		(at 31.6738 -99.6442 90)
		(property "Reference" "R47"
			(at 0 0 90)
			(layer "F.SilkS")
			(hide yes)
			(effects
				(font
					(size 1.27 1.27)
				)
			)
		)
		(property "Value" "0R2J-2-GP"
			(at 0.064008 -3.993896 90)
			(unlocked yes)
			(layer "F.Fab")
			(hide yes)
			(effects
				(font
					(size 1.016 1.016)
					(thickness 0.1524)
				)
			)
		)
		(property "Device Type" "R402H16"
			(at 0.064008 -5.517896 90)
			(unlocked yes)
			(layer "F.Fab")
			(hide yes)
			(effects
				(font
					(size 1.016 1.016)
					(thickness 0.1524)
				)
			)
		)
		(duplicate_pad_numbers_are_jumpers no)
		(fp_line
			(start 0.508 -0.9398)
			(end -0.508 -0.9398)
			(stroke
				(width 0.1524)
				(type default)
			)
			(layer "F.SilkS")
		)
		(fp_line
			(start -0.508 -0.9398)
			(end -0.508 0.9398)
			(stroke
				(width 0.1524)
				(type default)
			)
			(layer "F.SilkS")
		)
		(fp_rect
			(start -0.508 0.9398)
			(end 0.508 -0.9398)
			(stroke
				(width 0)
				(type default)
			)
			(fill no)
			(layer "F.CrtYd")
		)
		(fp_rect
			(start -0.508 0.9398)
			(end 0.508 -0.9398)
			(stroke
				(width 0)
				(type default)
			)
			(fill no)
			(layer "F.Fab")
		)
		(pad "1" smd custom
			(at 0 -0.4445 90)
			(size 0.1397 0.1397)
			(layers "F.Cu" "F.Mask" "F.Paste")
			(net "NVM_CS_N_R")
			(options
				(clearance outline)
				(anchor circle)
			)
			(primitives
				(gr_poly
					(pts
						(arc
							(start -0.1778 -0.2794)
							(mid -0.249642 -0.249642)
							(end -0.2794 -0.1778)
						)
						(arc
							(start -0.2794 0.1778)
							(mid -0.249642 0.249642)
							(end -0.1778 0.2794)
						)
						(arc
							(start 0.1778 0.2794)
							(mid 0.249642 0.249642)
							(end 0.2794 0.1778)
						)
						(arc
							(start 0.2794 -0.1778)
							(mid 0.249642 -0.249642)
							(end 0.1778 -0.2794)
						)
					)
					(width 0)
					(fill yes)
				)
			)
		)
		(pad "2" smd custom
			(at 0 0.4445 90)
			(size 0.1397 0.1397)
			(layers "F.Cu" "F.Mask" "F.Paste")
			(net "I2C_MUX_1A")
			(options
				(clearance outline)
				(anchor circle)
			)
			(primitives
				(gr_poly
					(pts
						(arc
							(start -0.1778 -0.2794)
							(mid -0.249642 -0.249642)
							(end -0.2794 -0.1778)
						)
						(arc
							(start -0.2794 0.1778)
							(mid -0.249642 0.249642)
							(end -0.1778 0.2794)
						)
						(arc
							(start 0.1778 0.2794)
							(mid 0.249642 0.249642)
							(end 0.2794 0.1778)
						)
						(arc
							(start 0.2794 -0.1778)
							(mid 0.249642 -0.249642)
							(end 0.1778 -0.2794)
						)
					)
					(width 0)
					(fill yes)
				)
			)
		)
	)
)
